(kicad_pcb
	(version 20221018)
	(generator pcbnew)
	(general
    (thickness 1.656)
  )
	(paper "A4")
	(title_block
    (title "SDI-MIPI Bridge")
    (date "2023-08-09")
    (rev "1.3.4")
    (company "Antmicro")
		(comment 9 "footprints 2-7 of 190")
	)
	(layers
    (0 "F.Cu" signal)
    (1 "In1.Cu" power)
    (2 "In2.Cu" power)
    (3 "In3.Cu" signal)
    (4 "In4.Cu" signal)
    (31 "B.Cu" signal)
    (32 "B.Adhes" user "B.Adhesive")
    (33 "F.Adhes" user "F.Adhesive")
    (34 "B.Paste" user)
    (35 "F.Paste" user)
    (36 "B.SilkS" user "B.Silkscreen")
    (37 "F.SilkS" user "F.Silkscreen")
    (38 "B.Mask" user)
    (39 "F.Mask" user)
    (40 "Dwgs.User" user "User.Drawings")
    (41 "Cmts.User" user "User.Comments")
    (42 "Eco1.User" user "User.Eco1")
    (43 "Eco2.User" user "User.Eco2")
    (44 "Edge.Cuts" user)
    (45 "Margin" user)
    (46 "B.CrtYd" user "B.Courtyard")
    (47 "F.CrtYd" user "F.Courtyard")
    (48 "B.Fab" user)
    (49 "F.Fab" user)
  )
	(footprint "sdi-mipi-bridge-footprints:Testpoint_smd_1mm" (layer "F.Cu")
    (at 122.435 123.6742 180)
    (property "Author" "Antmicro")
    (property "License" "Apache-2.0")
    (property "MPN" "")
    (property "Manufacturer" "")
    (property "Sheetfile" "sdi-mipi-bridge.kicad_sch")
    (property "Sheetname" "")
    (property "ki_description" "Test Point 1mm")
    (attr smd)
    (fp_text reference "TP17" (at 0.635 -0.3258) (layer "F.SilkS")
        (effects (font (size 0.65 0.65) (thickness 0.15)) (justify right bottom))
    )
    (fp_text value "TP_1mm_SMD" (at 0 1.4) (layer "F.Fab") hide
        (effects (font (size 0.7 0.7) (thickness 0.15)) (justify right bottom))
    )
    (fp_text user "${REFERENCE}" (at -0.5 2.8) (layer "F.Fab") hide
        (effects (font (size 0.7 0.7) (thickness 0.15)) (justify right bottom))
    )
    (fp_text user "License: Apache-2.0" (at -0.5 5.2) (layer "F.Fab") hide
        (effects (font (size 0.7 0.7) (thickness 0.15)) (justify right bottom))
    )
    (fp_text user "Author: Antmicro" (at -0.5 4) (layer "F.Fab") hide
        (effects (font (size 0.7 0.7) (thickness 0.15)) (justify right bottom))
    )
    (pad "1" smd circle (at 0 0 180) (size 1 1) (layers "F.Cu" "F.Mask")
      (net 130 "Net-(U2B-XTAL_OUT)") (pinfunction "1") (pintype "passive"))
  )
	(footprint "sdi-mipi-bridge-footprints:Testpoint_smd_1mm" (layer "F.Cu")
    (at 122.5 107.3492 180)
    (property "Author" "Antmicro")
    (property "License" "Apache-2.0")
    (property "MPN" "")
    (property "Manufacturer" "")
    (property "Sheetfile" "sdi-mipi-bridge.kicad_sch")
    (property "Sheetname" "")
    (property "ki_description" "Test Point 1mm")
    (attr smd)
    (fp_text reference "TP2" (at -1.1 -0.3508 180) (layer "F.SilkS")
        (effects (font (size 0.65 0.65) (thickness 0.15)) (justify left bottom))
    )
    (fp_text value "TP_1mm_SMD" (at 0 1.4 180) (layer "F.Fab") hide
        (effects (font (size 0.7 0.7) (thickness 0.15)) (justify left bottom))
    )
    (fp_text user "${REFERENCE}" (at -0.5 2.8 180) (layer "F.Fab") hide
        (effects (font (size 0.7 0.7) (thickness 0.15)) (justify left bottom))
    )
    (fp_text user "Author: Antmicro" (at -0.5 4 180) (layer "F.Fab") hide
        (effects (font (size 0.7 0.7) (thickness 0.15)) (justify left bottom))
    )
    (fp_text user "License: Apache-2.0" (at -0.5 5.2 180) (layer "F.Fab") hide
        (effects (font (size 0.7 0.7) (thickness 0.15)) (justify left bottom))
    )
    (pad "1" smd circle (at 0 0 180) (size 1 1) (layers "F.Cu" "F.Mask")
      (net 15 "/V_VSYNC") (pinfunction "1") (pintype "passive"))
  )
	(footprint "sdi-mipi-bridge-footprints:C_0402_1005Metric" (layer "F.Cu")
    (at 116.5 106.4 90)
    (descr "Capacitor SMD 0402")
    (tags "capacitor SMD 0402")
    (property "Author" "Antmicro")
    (property "Dielectric" "")
    (property "License" "Apache-2.0")
    (property "MPN" "C1005X6S1A105K050BC")
    (property "Manufacturer" "TDK")
    (property "Sheetfile" "sdi-mipi-bridge.kicad_sch")
    (property "Sheetname" "")
    (property "Val" "1u")
    (property "Voltage" "")
    (property "ki_description" " ")
    (attr smd)
    (fp_text reference "C62" (at -2.9 0.4 90) (layer "F.SilkS")
        (effects (font (size 0.65 0.65) (thickness 0.15)) (justify left bottom))
    )
    (fp_text value "C_1u_0402" (at 0 1.4 90) (layer "F.Fab") hide
        (effects (font (size 0.7 0.7) (thickness 0.15)) (justify left bottom))
    )
    (fp_text user "License: Apache-2.0" (at -0.932 5.17 90) (layer "F.Fab") hide
        (effects (font (size 0.7 0.7) (thickness 0.15)) (justify left bottom))
    )
    (fp_text user "Author: Antmicro" (at -0.932 4.17 90) (layer "F.Fab") hide
        (effects (font (size 0.7 0.7) (thickness 0.15)) (justify left bottom))
    )
    (fp_text user "${REFERENCE}" (at -0.932 3.168 90) (layer "F.Fab") hide
        (effects (font (size 0.7 0.7) (thickness 0.15)) (justify left bottom))
    )
    (fp_rect (start -0.94 -0.47) (end 0.94 0.47)
      (stroke (width 0.05) (type solid)) (fill none) (layer "F.CrtYd"))
    (fp_rect (start -0.499 -0.249) (end 0.499 0.249)
      (stroke (width 0.15) (type solid)) (fill none) (layer "F.Fab"))
    (pad "1" smd roundrect (at -0.484 0 90) (size 0.59 0.64) (layers "F.Cu" "F.Paste" "F.Mask") (roundrect_rratio 0.25)
      (net 11 "/VBG") (pintype "passive"))
    (pad "2" smd roundrect (at 0.484 0 90) (size 0.59 0.64) (layers "F.Cu" "F.Paste" "F.Mask") (roundrect_rratio 0.25)
      (net 3 "GNDA") (pintype "passive"))
  )
	(footprint "sdi-mipi-bridge-footprints:R_0402_1005Metric" (layer "F.Cu")
    (at 119.5 106.4 -90)
    (descr "Resistor SMD 0402")
    (tags "resistor SMD 0402")
    (property "Author" "Antmicro")
    (property "Current" "1A")
    (property "DNP" "DNP")
    (property "License" "Apache-2.0")
    (property "MPN" "ERJ2GE0R00X")
    (property "Manufacturer" "Panasonic")
    (property "Sheetfile" "sdi-mipi-bridge.kicad_sch")
    (property "Sheetname" "")
    (property "Tolerance" "")
    (property "Val" "0R")
    (property "ki_description" "0R resistor in 0402 package with unspecified tolerance")
    (attr exclude_from_pos_files)
    (fp_text reference "R32" (at 2.9 -0.4 -90) (layer "F.SilkS")
        (effects (font (size 0.65 0.65) (thickness 0.15)) (justify left bottom))
    )
    (fp_text value "R_0R_0402" (at 0 1.4 -90) (layer "F.Fab") hide
        (effects (font (size 0.7 0.7) (thickness 0.15)) (justify left bottom))
    )
    (fp_text user "${REFERENCE}" (at -0.95 3.168 -90) (layer "F.Fab") hide
        (effects (font (size 0.7 0.7) (thickness 0.15)) (justify left bottom))
    )
    (fp_text user "License: Apache-2.0" (at -0.95 5.169 -90) (layer "F.Fab") hide
        (effects (font (size 0.7 0.7) (thickness 0.15)) (justify left bottom))
    )
    (fp_text user "Author: Antmicro" (at -0.95 4.169 -90) (layer "F.Fab") hide
        (effects (font (size 0.7 0.7) (thickness 0.15)) (justify left bottom))
    )
    (fp_rect (start -0.93 -0.47) (end 0.93 0.47)
      (stroke (width 0.05) (type solid)) (fill none) (layer "F.CrtYd"))
    (fp_rect (start -0.5 -0.25) (end 0.5 0.25)
      (stroke (width 0.15) (type solid)) (fill none) (layer "F.Fab"))
    (pad "1" smd roundrect (at -0.485 0 270) (size 0.59 0.64) (layers "F.Cu" "F.Paste" "F.Mask") (roundrect_rratio 0.25)
      (net 3 "GNDA") (pintype "passive"))
    (pad "2" smd roundrect (at 0.485 0 270) (size 0.59 0.64) (layers "F.Cu" "F.Paste" "F.Mask") (roundrect_rratio 0.25)
      (net 40 "/LB_CONT") (pintype "passive"))
  )
	(footprint "sdi-mipi-bridge-footprints:R_0402_1005Metric" (layer "F.Cu")
    (at 118.5 106.4 -90)
    (descr "Resistor SMD 0402")
    (tags "resistor SMD 0402")
    (property "Author" "Antmicro")
    (property "Current" "1A")
    (property "DNP" "DNP")
    (property "License" "Apache-2.0")
    (property "MPN" "ERJ2GE0R00X")
    (property "Manufacturer" "Panasonic")
    (property "Sheetfile" "sdi-mipi-bridge.kicad_sch")
    (property "Sheetname" "")
    (property "Tolerance" "")
    (property "Val" "0R")
    (property "ki_description" "0R resistor in 0402 package with unspecified tolerance")
    (attr exclude_from_pos_files)
    (fp_text reference "R34" (at 2.9 -0.4 -90) (layer "F.SilkS")
        (effects (font (size 0.65 0.65) (thickness 0.15)) (justify left bottom))
    )
    (fp_text value "R_0R_0402" (at 0 1.4 -90) (layer "F.Fab") hide
        (effects (font (size 0.7 0.7) (thickness 0.15)) (justify left bottom))
    )
    (fp_text user "${REFERENCE}" (at -0.95 3.168 -90) (layer "F.Fab") hide
        (effects (font (size 0.7 0.7) (thickness 0.15)) (justify left bottom))
    )
    (fp_text user "License: Apache-2.0" (at -0.95 5.169 -90) (layer "F.Fab") hide
        (effects (font (size 0.7 0.7) (thickness 0.15)) (justify left bottom))
    )
    (fp_text user "Author: Antmicro" (at -0.95 4.169 -90) (layer "F.Fab") hide
        (effects (font (size 0.7 0.7) (thickness 0.15)) (justify left bottom))
    )
    (fp_rect (start -0.93 -0.47) (end 0.93 0.47)
      (stroke (width 0.05) (type solid)) (fill none) (layer "F.CrtYd"))
    (fp_rect (start -0.5 -0.25) (end 0.5 0.25)
      (stroke (width 0.15) (type solid)) (fill none) (layer "F.Fab"))
    (pad "1" smd roundrect (at -0.485 0 270) (size 0.59 0.64) (layers "F.Cu" "F.Paste" "F.Mask") (roundrect_rratio 0.25)
      (net 5 "+3.3VA") (pintype "passive"))
    (pad "2" smd roundrect (at 0.485 0 270) (size 0.59 0.64) (layers "F.Cu" "F.Paste" "F.Mask") (roundrect_rratio 0.25)
      (net 40 "/LB_CONT") (pintype "passive"))
  )
	(footprint "sdi-mipi-bridge-footprints:Testpoint_smd_1mm" (layer "F.Cu")
    (at 122.5 105.8492 180)
    (property "Author" "Antmicro")
    (property "License" "Apache-2.0")
    (property "MPN" "")
    (property "Manufacturer" "")
    (property "Sheetfile" "sdi-mipi-bridge.kicad_sch")
    (property "Sheetname" "")
    (property "ki_description" "Test Point 1mm")
    (attr smd)
    (fp_text reference "TP1" (at -1.1 -0.3508 180) (layer "F.SilkS")
        (effects (font (size 0.65 0.65) (thickness 0.15)) (justify left bottom))
    )
    (fp_text value "TP_1mm_SMD" (at 0 1.4 180) (layer "F.Fab") hide
        (effects (font (size 0.7 0.7) (thickness 0.15)) (justify left bottom))
    )
    (fp_text user "Author: Antmicro" (at -0.5 4 180) (layer "F.Fab") hide
        (effects (font (size 0.7 0.7) (thickness 0.15)) (justify left bottom))
    )
    (fp_text user "License: Apache-2.0" (at -0.5 5.2 180) (layer "F.Fab") hide
        (effects (font (size 0.7 0.7) (thickness 0.15)) (justify left bottom))
    )
    (fp_text user "${REFERENCE}" (at -0.5 2.8 180) (layer "F.Fab") hide
        (effects (font (size 0.7 0.7) (thickness 0.15)) (justify left bottom))
    )
    (pad "1" smd circle (at 0 0 180) (size 1 1) (layers "F.Cu" "F.Mask")
      (net 14 "/H_HSYNC") (pinfunction "1") (pintype "passive"))
  )
)
